# T6G (Grand Teton) — schematic netlist excerpt (pin names and nets, part order shuffled) for the footprints in the layout excerpt that follows; sources: Cadence DE-HDL packaged netlist, KiCad conversion of 04192023_DAF0TMB3IC0_F0TG_MB_C_brd_V02_OCP.brd

U6001  CYUSB330468LTXI  CYUSB3304-68LTXI IC  pkg QFN68_TH_0-4_8X8  page 176
  DVDD12_1  = P1V2_CPU0_USB_DVDD12
  RREF_USB2  = USB_CPU0_HUB1_RREF_USB2
  DVDD12_2  = P1V2_CPU0_USB_DVDD12
  AVDD33_1  = P3V3_AUX_CPU0_USB_AVDD33
  US_TXM  = USB3_CPU0_BMC_RX_HUB1_DN
  US_TXP  = USB3_CPU0_BMC_RX_HUB1_DP
  DVDD12_5  = P1V2_AUX
  US_RXM  = USB3_CPU0_BMC_TX_C1_DN
  US_RXP  = USB3_CPU0_BMC_TX_C1_DP
  AVDD12_1  = P1V2_AUX
  DS4_TXP  = NC
  DS4_TXM  = NC
  DVDD12_6  = P1V2_AUX
  DS4_RXM  = NC
  DS4_RXP  = NC
  AVDD12_2  = P1V2_AUX
  VBUS_US  = USB_CPU0_HUB1_VBUS_US
  VBUS_DS  = USB_CPU0_HUB1_VBUS_DS
  VDD_EFUSE  = P1V2_CPU0_USB_DVDD12
  SUSPEND  = TP_CPU0_USB_HUB1_SUSPEND
  RESERVED1  = PU_CPU0_USB_HUB_RESERVED1
  RESERVED2  = PU_CPU0_USB_HUB_RESERVED2
  MODE_SEL0  = USB_CPU0_HUB1_MODE_SEL0
  MODE_SEL1  = USB_CPU0_HUB1_MODE_SEL1
  NC_25  = NC
  RREF_SS  = USB_CPU0_HUB1_RREF_SS
  DVDD12_3  = P1V2_CPU0_USB_DVDD12
  VDD_IO  = P3V3_AUX
  PWR_EN  = PU_CPU0_USB_HUB_PWR_EN
  OVRCURR  = PU_CPU0_USB_HUB_OVRCURR
  \reset#\  = RST_USB_CPU0_HUB1_R_N
  I2C_CLK  = SMB_USB_CPU0_HUB1_SCL
  I2C_DATA  = SMB_USB_CPU0_HUB1_SDA
  AVDD12_3  = P1V2_AUX
  DS3_RXP  = NC
  DS3_RXM  = NC
  DVDD12_7  = P1V2_AUX
  DS3_TXP  = NC
  DS3_TXM  = NC
  GND  = GND
  DS2_TXP  = NC
  DS2_TXM  = NC
  DVDD12_8  = P1V2_AUX
  DS2_RXM  = NC
  DS2_RXP  = NC
  AVDD12_4  = P1V2_AUX
  DS1_TXP  = USB3_CPU0_BMC_HUB1_TX_DP
  DS1_TXM  = USB3_CPU0_BMC_HUB1_TX_DN
  DVDD12_4  = P1V2_AUX
  DS1_RXM  = USB3_CPU0_BMC_RX_C1_DN
  DS1_RXP  = USB3_CPU0_BMC_RX_C1_DP
  AVDD12_5  = P1V2_AUX
  AVDD12_6  = P1V2_AUX
  XTL_OUT  = XTAL_USB_CPU0_HUB1_XOUT
  XTL_IN  = XTAL_USB_CPU0_HUB1_XIN
  AVDD33_2  = P3V3_AUX
  US_DP  = USB2_CPU0_P0_R1_DP
  US_DM  = USB2_CPU0_P0_R1_DN
  DS1_DM  = USB2_CPU0_P0_HUB1_R_DN
  DS1_DP  = USB2_CPU0_P0_HUB1_R_DP
  AVDD33_3  = P3V3_AUX
  DS2_DP  = NC
  DS2_DM  = NC
  DS3_DM  = NC
  DS3_DP  = NC
  AVDD33_4  = P3V3_AUX
  DS4_DP  = NC
  DS4_DM  = NC
  EPAD  = GND

(kicad_pcb
	(version 20260206)
	(generator "pcbnew")
	(generator_version "10.0")
	(general
		(thickness 1.6)
		(legacy_teardrops no)
	)
	(paper "A4")
	(title_block
		(title "04192023_DAF0TMB3IC0_F0TG_MB_C_brd_V02_OCP.brd")
		(comment 1 "Grand Teton / footprint 3444 of 8354 (U6001), pads 46-69 of 69")
	)
	(layers
		(0 "F.Cu" signal "TOP")
		(4 "In1.Cu" signal "GND")
		(6 "In2.Cu" signal "IN1")
		(8 "In3.Cu" signal "GND1")
		(10 "In4.Cu" signal "IN2")
		(12 "In5.Cu" signal "GND2")
		(14 "In6.Cu" signal "IN3")
		(16 "In7.Cu" signal "GND3")
		(18 "In8.Cu" signal "VCC")
		(20 "In9.Cu" signal "VCC1")
		(22 "In10.Cu" signal "GND4")
		(24 "In11.Cu" signal "IN4")
		(26 "In12.Cu" signal "GND5")
		(28 "In13.Cu" signal "IN5")
		(30 "In14.Cu" signal "GND6")
		(32 "In15.Cu" signal "IN6")
		(34 "In16.Cu" signal "GND7")
		(2 "B.Cu" signal "BOTTOM")
		(9 "F.Adhes" user "F.Adhesive")
		(11 "B.Adhes" user "B.Adhesive")
		(13 "F.Paste" user "Package Geometry/Pastemask Top")
		(15 "B.Paste" user "Package Geometry/Pastemask Bottom")
		(5 "F.SilkS" user "Ref Des/Silkscreen Top")
		(7 "B.SilkS" user "Ref Des/Silkscreen Bottom")
		(1 "F.Mask" user "Board Geometry/Soldermask Top")
		(3 "B.Mask" user "Board Geometry/Soldermask Bottom")
		(17 "Dwgs.User" user "User.Drawings")
		(19 "Cmts.User" user "User.Comments")
		(21 "Eco1.User" user "User.Eco1")
		(23 "Eco2.User" user "User.Eco2")
		(25 "Edge.Cuts" user "Board Geometry/Outline")
		(27 "Margin" user)
		(31 "F.CrtYd" user "Package Geometry/Place Bound Top")
		(29 "B.CrtYd" user "Package Geometry/Place Bound Bottom")
		(35 "F.Fab" user "Ref Des/Assembly Top")
		(33 "B.Fab" user "Ref Des/Assembly Bottom")
	)
	(footprint ""
		(layer "F.Cu")
		(at 132.694172 -36.873434 180)
		(property "Reference" "U6001"
			(at -4.192016 6.04266 0)
			(unlocked yes)
			(layer "F.SilkS")
			(effects
				(font
					(size 0.7874 0.5842)
					(thickness 0.1524)
				)
				(justify left)
			)
		)
		(property "Value" ""
			(at 0 0 180)
			(layer "F.Fab")
			(effects
				(font
					(size 1.27 1.27)
				)
			)
		)
		(duplicate_pad_numbers_are_jumpers no)
		(pad "46" smd rect
			(at 3.849878 -1.199896 270)
			(size 0.1778 1.3208)
			(layers "F.Cu" "F.Mask" "F.Paste")
			(net "P1V2_AUX")
		)
		(pad "47" smd rect
			(at 3.849878 -1.599946 270)
			(size 0.1778 1.3208)
			(layers "F.Cu" "F.Mask" "F.Paste")
			(net "USB3_CPU0_BMC_HUB1_TX_DP")
		)
		(pad "48" smd rect
			(at 3.849878 -1.999996 270)
			(size 0.1778 1.3208)
			(layers "F.Cu" "F.Mask" "F.Paste")
			(net "USB3_CPU0_BMC_HUB1_TX_DN")
		)
		(pad "49" smd rect
			(at 3.849878 -2.400046 270)
			(size 0.1778 1.3208)
			(layers "F.Cu" "F.Mask" "F.Paste")
			(net "P1V2_AUX")
		)
		(pad "50" smd rect
			(at 3.849878 -2.800096 270)
			(size 0.1778 1.3208)
			(layers "F.Cu" "F.Mask" "F.Paste")
			(net "USB3_CPU0_BMC_RX_C1_DN")
		)
		(pad "51" smd rect
			(at 3.999992 -3.199892 270)
			(size 0.1778 1.016)
			(layers "F.Cu" "F.Mask" "F.Paste")
			(net "USB3_CPU0_BMC_RX_C1_DP")
		)
		(pad "52" smd rect
			(at 3.199892 -3.999992 180)
			(size 0.1778 1.016)
			(layers "F.Cu" "F.Mask" "F.Paste")
			(net "P1V2_AUX")
		)
		(pad "53" smd rect
			(at 2.800096 -3.849878 180)
			(size 0.1778 1.3208)
			(layers "F.Cu" "F.Mask" "F.Paste")
			(net "P1V2_AUX")
		)
		(pad "54" smd rect
			(at 2.400046 -3.849878 180)
			(size 0.1778 1.3208)
			(layers "F.Cu" "F.Mask" "F.Paste")
			(net "XTAL_USB_CPU0_HUB1_XOUT")
		)
		(pad "55" smd rect
			(at 1.999996 -3.849878 180)
			(size 0.1778 1.3208)
			(layers "F.Cu" "F.Mask" "F.Paste")
			(net "XTAL_USB_CPU0_HUB1_XIN")
		)
		(pad "56" smd rect
			(at 1.599946 -3.849878 180)
			(size 0.1778 1.3208)
			(layers "F.Cu" "F.Mask" "F.Paste")
			(net "P3V3_AUX")
		)
		(pad "57" smd rect
			(at 1.199896 -3.849878 180)
			(size 0.1778 1.3208)
			(layers "F.Cu" "F.Mask" "F.Paste")
			(net "USB2_CPU0_P0_R1_DP")
		)
		(pad "58" smd rect
			(at 0.8001 -3.849878 180)
			(size 0.1778 1.3208)
			(layers "F.Cu" "F.Mask" "F.Paste")
			(net "USB2_CPU0_P0_R1_DN")
		)
		(pad "59" smd rect
			(at 0.40005 -3.849878 180)
			(size 0.1778 1.3208)
			(layers "F.Cu" "F.Mask" "F.Paste")
			(net "USB2_CPU0_P0_HUB1_R_DN")
		)
		(pad "60" smd rect
			(at 0 -3.849878 180)
			(size 0.1778 1.3208)
			(layers "F.Cu" "F.Mask" "F.Paste")
			(net "USB2_CPU0_P0_HUB1_R_DP")
		)
		(pad "61" smd rect
			(at -0.40005 -3.849878 180)
			(size 0.1778 1.3208)
			(layers "F.Cu" "F.Mask" "F.Paste")
			(net "P3V3_AUX")
		)
		(pad "62" smd rect
			(at -0.8001 -3.849878 180)
			(size 0.1778 1.3208)
			(layers "F.Cu" "F.Mask" "F.Paste")
			(net "Net_10815")
		)
		(pad "63" smd rect
			(at -1.199896 -3.849878 180)
			(size 0.1778 1.3208)
			(layers "F.Cu" "F.Mask" "F.Paste")
			(net "Net_10816")
		)
		(pad "64" smd rect
			(at -1.599946 -3.849878 180)
			(size 0.1778 1.3208)
			(layers "F.Cu" "F.Mask" "F.Paste")
			(net "Net_10810")
		)
		(pad "65" smd rect
			(at -1.999996 -3.849878 180)
			(size 0.1778 1.3208)
			(layers "F.Cu" "F.Mask" "F.Paste")
			(net "Net_10809")
		)
		(pad "66" smd rect
			(at -2.400046 -3.849878 180)
			(size 0.1778 1.3208)
			(layers "F.Cu" "F.Mask" "F.Paste")
			(net "P3V3_AUX")
		)
		(pad "67" smd rect
			(at -2.800096 -3.849878 180)
			(size 0.1778 1.3208)
			(layers "F.Cu" "F.Mask" "F.Paste")
			(net "Net_10803")
		)
		(pad "68" smd rect
			(at -3.199892 -3.999992 180)
			(size 0.1778 1.016)
			(layers "F.Cu" "F.Mask" "F.Paste")
			(net "Net_10804")
		)
		(pad "TH" smd rect
			(at 0 0 180)
			(size 5.207 5.207)
			(layers "F.Cu" "F.Mask" "F.Paste")
			(net "GND")
		)
	)
)
